# T6G (Grand Teton) — schematic netlist excerpt (pin names and nets, part order shuffled) for the footprints in the layout excerpt that follows; sources: Cadence DE-HDL packaged netlist, KiCad conversion of 04192023_DAF0TMB3IC0_F0TG_MB_C_brd_V02_OCP.brd

PR201  Q_RES  2.2 1% CHIP  pkg 0402LF  page 213 : A = PVDDCR_CPU0_P1_PVCC ; B = PVDDCR_CPU0_P1_VCC5
R6021  Q_RES  2K 5% EMPTY  pkg 0402LF  page 151 : A = P3V3_AUX ; B = SGPIO_SCM_CLK_<1>
C6752  Q_CAP_DIFFBUS  DIFF BUS_0.22UF 6.3V 20% X6S  pkg C0201  page 352 : \1\ = P5E_CPU1_P3_TX_BUF_C_DN<13> ; \2\ = P5E_CPU1_P3_TX_BUF_DN<13>

(kicad_pcb
	(version 20260206)
	(generator "pcbnew")
	(generator_version "10.0")
	(general
		(thickness 1.6)
		(legacy_teardrops no)
	)
	(paper "A4")
	(title_block
		(title "04192023_DAF0TMB3IC0_F0TG_MB_C_brd_V02_OCP.brd")
		(comment 1 "Grand Teton / footprints 5400-5402 of 8354")
	)
	(layers
		(0 "F.Cu" signal "TOP")
		(4 "In1.Cu" signal "GND")
		(6 "In2.Cu" signal "IN1")
		(8 "In3.Cu" signal "GND1")
		(10 "In4.Cu" signal "IN2")
		(12 "In5.Cu" signal "GND2")
		(14 "In6.Cu" signal "IN3")
		(16 "In7.Cu" signal "GND3")
		(18 "In8.Cu" signal "VCC")
		(20 "In9.Cu" signal "VCC1")
		(22 "In10.Cu" signal "GND4")
		(24 "In11.Cu" signal "IN4")
		(26 "In12.Cu" signal "GND5")
		(28 "In13.Cu" signal "IN5")
		(30 "In14.Cu" signal "GND6")
		(32 "In15.Cu" signal "IN6")
		(34 "In16.Cu" signal "GND7")
		(2 "B.Cu" signal "BOTTOM")
		(9 "F.Adhes" user "F.Adhesive")
		(11 "B.Adhes" user "B.Adhesive")
		(13 "F.Paste" user "Package Geometry/Pastemask Top")
		(15 "B.Paste" user "Package Geometry/Pastemask Bottom")
		(5 "F.SilkS" user "Ref Des/Silkscreen Top")
		(7 "B.SilkS" user "Ref Des/Silkscreen Bottom")
		(1 "F.Mask" user "Board Geometry/Soldermask Top")
		(3 "B.Mask" user "Board Geometry/Soldermask Bottom")
		(17 "Dwgs.User" user "User.Drawings")
		(19 "Cmts.User" user "User.Comments")
		(21 "Eco1.User" user "User.Eco1")
		(23 "Eco2.User" user "User.Eco2")
		(25 "Edge.Cuts" user "Board Geometry/Outline")
		(27 "Margin" user)
		(31 "F.CrtYd" user "Package Geometry/Place Bound Top")
		(29 "B.CrtYd" user "Package Geometry/Place Bound Bottom")
		(35 "F.Fab" user "Ref Des/Assembly Top")
		(33 "B.Fab" user "Ref Des/Assembly Bottom")
	)
	(footprint ""
		(layer "B.Cu")
		(at 171.577 -98.135948 90)
		(property "Reference" "R6021"
			(at 0 0 90)
			(layer "B.SilkS")
			(hide yes)
			(effects
				(font
					(size 1.27 1.27)
				)
				(justify mirror)
			)
		)
		(property "Value" ""
			(at 0 0 90)
			(layer "B.Fab")
			(effects
				(font
					(size 1.27 1.27)
				)
				(justify mirror)
			)
		)
		(duplicate_pad_numbers_are_jumpers no)
		(fp_line
			(start 0.7874 -0.4064)
			(end -0.7874 -0.4064)
			(stroke
				(width 0.1524)
				(type default)
			)
			(layer "B.SilkS")
		)
		(fp_line
			(start -0.7874 -0.4064)
			(end -0.7874 0.4064)
			(stroke
				(width 0.1524)
				(type default)
			)
			(layer "B.SilkS")
		)
		(fp_line
			(start 0.7874 0.4064)
			(end 0.7874 -0.4064)
			(stroke
				(width 0.1524)
				(type default)
			)
			(layer "B.SilkS")
		)
		(fp_line
			(start -0.7874 0.4064)
			(end 0.7874 0.4064)
			(stroke
				(width 0.1524)
				(type default)
			)
			(layer "B.SilkS")
		)
		(fp_line
			(start 0.67945 -0.305054)
			(end 0.12065 -0.305054)
			(stroke
				(width 0.1)
				(type default)
			)
			(layer "B.Fab")
		)
		(fp_line
			(start 0.12065 -0.305054)
			(end 0.12065 -0.2794)
			(stroke
				(width 0.1)
				(type default)
			)
			(layer "B.Fab")
		)
		(fp_line
			(start -0.12065 -0.3048)
			(end -0.67945 -0.3048)
			(stroke
				(width 0.1)
				(type default)
			)
			(layer "B.Fab")
		)
		(fp_line
			(start -0.67945 -0.3048)
			(end -0.67945 0.3048)
			(stroke
				(width 0.1)
				(type default)
			)
			(layer "B.Fab")
		)
		(fp_line
			(start 0.12065 -0.2794)
			(end -0.12065 -0.2794)
			(stroke
				(width 0.1)
				(type default)
			)
			(layer "B.Fab")
		)
		(fp_line
			(start -0.12065 -0.2794)
			(end -0.12065 -0.3048)
			(stroke
				(width 0.1)
				(type default)
			)
			(layer "B.Fab")
		)
		(fp_line
			(start 0.12065 0.2794)
			(end 0.12065 0.3048)
			(stroke
				(width 0.1)
				(type default)
			)
			(layer "B.Fab")
		)
		(fp_line
			(start -0.120396 0.2794)
			(end 0.12065 0.2794)
			(stroke
				(width 0.1)
				(type default)
			)
			(layer "B.Fab")
		)
		(fp_line
			(start 0.67945 0.3048)
			(end 0.67945 -0.305054)
			(stroke
				(width 0.1)
				(type default)
			)
			(layer "B.Fab")
		)
		(fp_line
			(start 0.12065 0.3048)
			(end 0.67945 0.3048)
			(stroke
				(width 0.1)
				(type default)
			)
			(layer "B.Fab")
		)
		(fp_line
			(start -0.120396 0.3048)
			(end -0.120396 0.2794)
			(stroke
				(width 0.1)
				(type default)
			)
			(layer "B.Fab")
		)
		(fp_line
			(start -0.67945 0.3048)
			(end -0.120396 0.3048)
			(stroke
				(width 0.1)
				(type default)
			)
			(layer "B.Fab")
		)
		(pad "1" smd circle
			(at 0.40005 0 270)
			(size 0 0)
			(layers "B.Cu" "B.Mask" "B.Paste")
			(net "P3V3_AUX")
		)
		(pad "2" smd circle
			(at -0.40005 0 270)
			(size 0 0)
			(layers "B.Cu" "B.Mask" "B.Paste")
			(net "SGPIO_SCM_CLK_<1>")
		)
	)
	(footprint ""
		(layer "B.Cu")
		(at 156.222446 -408.517344 90)
		(property "Reference" "C6752"
			(at 0 0 90)
			(layer "B.SilkS")
			(hide yes)
			(effects
				(font
					(size 1.27 1.27)
				)
				(justify mirror)
			)
		)
		(property "Value" ""
			(at 0 0 90)
			(layer "B.Fab")
			(effects
				(font
					(size 1.27 1.27)
				)
				(justify mirror)
			)
		)
		(duplicate_pad_numbers_are_jumpers no)
		(fp_line
			(start 0.299974 -0.150114)
			(end -0.299974 -0.150114)
			(stroke
				(width 0.1)
				(type default)
			)
			(layer "B.Fab")
		)
		(fp_line
			(start -0.299974 -0.150114)
			(end -0.299974 0.150114)
			(stroke
				(width 0.1)
				(type default)
			)
			(layer "B.Fab")
		)
		(fp_line
			(start 0.299974 0.150114)
			(end 0.299974 -0.150114)
			(stroke
				(width 0.1)
				(type default)
			)
			(layer "B.Fab")
		)
		(fp_line
			(start -0.299974 0.150114)
			(end 0.299974 0.150114)
			(stroke
				(width 0.1)
				(type default)
			)
			(layer "B.Fab")
		)
		(pad "1" smd rect
			(at 0.2667 0 270)
			(size 0.3048 0.381)
			(layers "B.Cu" "B.Mask" "B.Paste")
			(net "P5E_CPU1_P3_TX_BUF_C_DN<13>")
		)
		(pad "2" smd rect
			(at -0.2667 0 270)
			(size 0.3048 0.381)
			(layers "B.Cu" "B.Mask" "B.Paste")
			(net "P5E_CPU1_P3_TX_BUF_DN<13>")
		)
	)
	(footprint ""
		(layer "B.Cu")
		(at 76.271882 -176.566576 90)
		(property "Reference" "PR201"
			(at 0 0 90)
			(layer "B.SilkS")
			(hide yes)
			(effects
				(font
					(size 1.27 1.27)
				)
				(justify mirror)
			)
		)
		(property "Value" ""
			(at 0 0 90)
			(layer "B.Fab")
			(effects
				(font
					(size 1.27 1.27)
				)
				(justify mirror)
			)
		)
		(duplicate_pad_numbers_are_jumpers no)
		(fp_line
			(start 0.7874 -0.4064)
			(end -0.7874 -0.4064)
			(stroke
				(width 0.1524)
				(type default)
			)
			(layer "B.SilkS")
		)
		(fp_line
			(start -0.7874 -0.4064)
			(end -0.7874 0.4064)
			(stroke
				(width 0.1524)
				(type default)
			)
			(layer "B.SilkS")
		)
		(fp_line
			(start 0.7874 0.4064)
			(end 0.7874 -0.4064)
			(stroke
				(width 0.1524)
				(type default)
			)
			(layer "B.SilkS")
		)
		(fp_line
			(start -0.7874 0.4064)
			(end 0.7874 0.4064)
			(stroke
				(width 0.1524)
				(type default)
			)
			(layer "B.SilkS")
		)
		(fp_line
			(start 0.67945 -0.305054)
			(end 0.12065 -0.305054)
			(stroke
				(width 0.1)
				(type default)
			)
			(layer "B.Fab")
		)
		(fp_line
			(start 0.12065 -0.305054)
			(end 0.12065 -0.2794)
			(stroke
				(width 0.1)
				(type default)
			)
			(layer "B.Fab")
		)
		(fp_line
			(start -0.12065 -0.3048)
			(end -0.67945 -0.3048)
			(stroke
				(width 0.1)
				(type default)
			)
			(layer "B.Fab")
		)
		(fp_line
			(start -0.67945 -0.3048)
			(end -0.67945 0.3048)
			(stroke
				(width 0.1)
				(type default)
			)
			(layer "B.Fab")
		)
		(fp_line
			(start 0.12065 -0.2794)
			(end -0.12065 -0.2794)
			(stroke
				(width 0.1)
				(type default)
			)
			(layer "B.Fab")
		)
		(fp_line
			(start -0.12065 -0.2794)
			(end -0.12065 -0.3048)
			(stroke
				(width 0.1)
				(type default)
			)
			(layer "B.Fab")
		)
		(fp_line
			(start 0.12065 0.2794)
			(end 0.12065 0.3048)
			(stroke
				(width 0.1)
				(type default)
			)
			(layer "B.Fab")
		)
		(fp_line
			(start -0.120396 0.2794)
			(end 0.12065 0.2794)
			(stroke
				(width 0.1)
				(type default)
			)
			(layer "B.Fab")
		)
		(fp_line
			(start 0.67945 0.3048)
			(end 0.67945 -0.305054)
			(stroke
				(width 0.1)
				(type default)
			)
			(layer "B.Fab")
		)
		(fp_line
			(start 0.12065 0.3048)
			(end 0.67945 0.3048)
			(stroke
				(width 0.1)
				(type default)
			)
			(layer "B.Fab")
		)
		(fp_line
			(start -0.120396 0.3048)
			(end -0.120396 0.2794)
			(stroke
				(width 0.1)
				(type default)
			)
			(layer "B.Fab")
		)
		(fp_line
			(start -0.67945 0.3048)
			(end -0.120396 0.3048)
			(stroke
				(width 0.1)
				(type default)
			)
			(layer "B.Fab")
		)
		(pad "1" smd circle
			(at 0.40005 0 270)
			(size 0 0)
			(layers "B.Cu" "B.Mask" "B.Paste")
			(net "PVDDCR_CPU0_P1_PVCC")
		)
		(pad "2" smd circle
			(at -0.40005 0 270)
			(size 0 0)
			(layers "B.Cu" "B.Mask" "B.Paste")
			(net "PVDDCR_CPU0_P1_VCC5")
		)
	)
)
